(kicad_pcb
	(version 20260206)
	(generator "pcbnew")
	(generator_version "10.0")
	(general
		(thickness 1.6)
		(legacy_teardrops no)
	)
	(paper "A4")
	(title_block
		(title "Wiwynn_Tioga_Pass_MB.brd")
		(comment 1 "Tioga Pass / footprints 314-319 of 4770")
	)
	(layers
		(0 "F.Cu" signal "TOP")
		(4 "In1.Cu" signal "L2GND")
		(6 "In2.Cu" signal "L3")
		(8 "In3.Cu" signal "L4GND")
		(10 "In4.Cu" signal "L5")
		(12 "In5.Cu" signal "L6GND")
		(14 "In6.Cu" signal "L7VCC")
		(16 "In7.Cu" signal "L8VCC")
		(18 "In8.Cu" signal "L9GND")
		(20 "In9.Cu" signal "L10")
		(22 "In10.Cu" signal "L11GND")
		(24 "In11.Cu" signal "L12")
		(26 "In12.Cu" signal "L13GND")
		(2 "B.Cu" signal "BOTTOM")
		(9 "F.Adhes" user "F.Adhesive")
		(11 "B.Adhes" user "B.Adhesive")
		(13 "F.Paste" user "Package Geometry/Pastemask Top")
		(15 "B.Paste" user "Package Geometry/Pastemask Bottom")
		(5 "F.SilkS" user "Ref Des/Silkscreen Top")
		(7 "B.SilkS" user "Ref Des/Silkscreen Bottom")
		(1 "F.Mask" user "Board Geometry/Soldermask Top")
		(3 "B.Mask" user "Board Geometry/Soldermask Bottom")
		(17 "Dwgs.User" user "User.Drawings")
		(19 "Cmts.User" user "User.Comments")
		(21 "Eco1.User" user "User.Eco1")
		(23 "Eco2.User" user "User.Eco2")
		(25 "Edge.Cuts" user "Board Geometry/Outline")
		(27 "Margin" user)
		(31 "F.CrtYd" user "Package Geometry/Place Bound Top")
		(29 "B.CrtYd" user "Package Geometry/Place Bound Bottom")
		(35 "F.Fab" user "Ref Des/Assembly Top")
		(33 "B.Fab" user "Ref Des/Assembly Bottom")
	)
	(footprint ""
		(layer "F.Cu")
		(at 26.289 -81.026 180)
		(property "Reference" "R1D22"
			(at 0 0 180)
			(layer "F.SilkS")
			(hide yes)
			(effects
				(font
					(size 1.27 1.27)
				)
			)
		)
		(property "Value" ""
			(at 0 0 180)
			(layer "F.Fab")
			(effects
				(font
					(size 1.27 1.27)
				)
			)
		)
		(duplicate_pad_numbers_are_jumpers no)
		(fp_poly
			(pts
				(xy -0.2794 -0.1016) (xy 0.2794 -0.1016) (xy 0.2794 0.9906) (xy -0.2794 0.9906)
			)
			(stroke
				(width 0)
				(type default)
			)
			(fill no)
			(layer "F.CrtYd")
		)
		(fp_line
			(start 0.2794 0.9906)
			(end 0.2794 -0.1016)
			(stroke
				(width 0.1)
				(type default)
			)
			(layer "F.Fab")
		)
		(fp_line
			(start 0.2794 -0.1016)
			(end -0.2794 -0.1016)
			(stroke
				(width 0.1)
				(type default)
			)
			(layer "F.Fab")
		)
		(fp_line
			(start -0.2794 0.9906)
			(end 0.2794 0.9906)
			(stroke
				(width 0.1)
				(type default)
			)
			(layer "F.Fab")
		)
		(fp_line
			(start -0.2794 -0.1016)
			(end -0.2794 0.9906)
			(stroke
				(width 0.1)
				(type default)
			)
			(layer "F.Fab")
		)
		(pad "1" smd rect
			(at 0 0 180)
			(size 0.508 0.508)
			(layers "F.Cu" "F.Mask" "F.Paste")
			(net "P3V3_STBY")
		)
		(pad "2" smd rect
			(at 0 0.889 180)
			(size 0.508 0.508)
			(layers "F.Cu" "F.Mask" "F.Paste")
			(net "FM_OC_DETECT_N")
		)
		(zone
			(layer "F.Cu")
			(hatch none 0.5)
			(connect_pads
				(clearance 0)
			)
			(min_thickness 0.25)
			(keepout
				(tracks not_allowed)
				(vias allowed)
				(pads allowed)
				(copperpour not_allowed)
				(footprints allowed)
			)
			(placement
				(enabled no)
				(sheetname "")
			)
			(fill
				(thermal_gap 0.5)
				(thermal_bridge_width 0.5)
				(island_removal_mode 0)
			)
			(polygon
				(pts
					(xy 26.543 -81.661) (xy 26.035 -81.661) (xy 26.035 -81.28) (xy 26.543 -81.28)
				)
			)
		)
		(zone
			(layer "F.Cu")
			(hatch none 0.5)
			(connect_pads
				(clearance 0)
			)
			(min_thickness 0.25)
			(keepout
				(tracks allowed)
				(vias not_allowed)
				(pads allowed)
				(copperpour not_allowed)
				(footprints allowed)
			)
			(placement
				(enabled no)
				(sheetname "")
			)
			(fill
				(thermal_gap 0.5)
				(thermal_bridge_width 0.5)
				(island_removal_mode 0)
			)
			(polygon
				(pts
					(xy 26.543 -81.28) (xy 26.035 -81.28) (xy 26.035 -81.661) (xy 26.543 -81.661)
				)
			)
		)
	)
	(footprint ""
		(layer "F.Cu")
		(at 400.430492 -10.917936)
		(property "Reference" "C8G1"
			(at 0 0 0)
			(layer "F.SilkS")
			(hide yes)
			(effects
				(font
					(size 1.27 1.27)
				)
			)
		)
		(property "Value" ""
			(at 0 0 0)
			(layer "F.Fab")
			(effects
				(font
					(size 1.27 1.27)
				)
			)
		)
		(duplicate_pad_numbers_are_jumpers no)
		(fp_rect
			(start -0.3048 0.9906)
			(end 0.3048 -0.1016)
			(stroke
				(width 0)
				(type default)
			)
			(fill no)
			(layer "F.CrtYd")
		)
		(fp_line
			(start -0.3048 -0.1016)
			(end -0.3048 0.9906)
			(stroke
				(width 0.1)
				(type default)
			)
			(layer "F.Fab")
		)
		(fp_line
			(start -0.3048 0.9906)
			(end 0.3048 0.9906)
			(stroke
				(width 0.1)
				(type default)
			)
			(layer "F.Fab")
		)
		(fp_line
			(start 0.3048 -0.1016)
			(end -0.3048 -0.1016)
			(stroke
				(width 0.1)
				(type default)
			)
			(layer "F.Fab")
		)
		(fp_line
			(start 0.3048 0.9906)
			(end 0.3048 -0.1016)
			(stroke
				(width 0.1)
				(type default)
			)
			(layer "F.Fab")
		)
		(pad "1" smd rect
			(at 0 0)
			(size 0.508 0.508)
			(layers "F.Cu" "F.Mask" "F.Paste")
			(net "P3E_CPU0_PE2_SS_TXP<4>")
		)
		(pad "2" smd rect
			(at 0 0.889)
			(size 0.508 0.508)
			(layers "F.Cu" "F.Mask" "F.Paste")
			(net "P3E_CPU0_PE2_SS_C_TXP<4>")
		)
		(zone
			(layer "F.Cu")
			(hatch none 0.5)
			(connect_pads
				(clearance 0)
			)
			(min_thickness 0.25)
			(keepout
				(tracks allowed)
				(vias not_allowed)
				(pads allowed)
				(copperpour not_allowed)
				(footprints allowed)
			)
			(placement
				(enabled no)
				(sheetname "")
			)
			(fill
				(thermal_gap 0.5)
				(thermal_bridge_width 0.5)
				(island_removal_mode 0)
			)
			(polygon
				(pts
					(xy 400.176492 -10.282936) (xy 400.684492 -10.282936) (xy 400.684492 -10.663936) (xy 400.176492 -10.663936)
				)
			)
		)
		(zone
			(layer "F.Cu")
			(hatch none 0.5)
			(connect_pads
				(clearance 0)
			)
			(min_thickness 0.25)
			(keepout
				(tracks not_allowed)
				(vias allowed)
				(pads allowed)
				(copperpour not_allowed)
				(footprints allowed)
			)
			(placement
				(enabled no)
				(sheetname "")
			)
			(fill
				(thermal_gap 0.5)
				(thermal_bridge_width 0.5)
				(island_removal_mode 0)
			)
			(polygon
				(pts
					(xy 400.176492 -10.282936) (xy 400.684492 -10.282936) (xy 400.684492 -10.663936) (xy 400.176492 -10.663936)
				)
			)
		)
	)
	(footprint ""
		(layer "F.Cu")
		(at -1.033526 -124.073666 90)
		(property "Reference" "RF21"
			(at -0.8382 -0.67818 90)
			(unlocked yes)
			(layer "F.SilkS")
			(effects
				(font
					(size 0.4064 0.254)
					(thickness 0.1524)
				)
				(justify left)
			)
		)
		(property "Value" ""
			(at 0 0 90)
			(layer "F.Fab")
			(effects
				(font
					(size 1.27 1.27)
				)
			)
		)
		(duplicate_pad_numbers_are_jumpers no)
		(fp_poly
			(pts
				(xy -0.2794 -0.1016) (xy 0.2794 -0.1016) (xy 0.2794 0.9906) (xy -0.2794 0.9906)
			)
			(stroke
				(width 0)
				(type default)
			)
			(fill no)
			(layer "F.CrtYd")
		)
		(fp_line
			(start 0.2794 -0.1016)
			(end -0.2794 -0.1016)
			(stroke
				(width 0.1)
				(type default)
			)
			(layer "F.Fab")
		)
		(fp_line
			(start -0.2794 -0.1016)
			(end -0.2794 0.9906)
			(stroke
				(width 0.1)
				(type default)
			)
			(layer "F.Fab")
		)
		(fp_line
			(start 0.2794 0.9906)
			(end 0.2794 -0.1016)
			(stroke
				(width 0.1)
				(type default)
			)
			(layer "F.Fab")
		)
		(fp_line
			(start -0.2794 0.9906)
			(end 0.2794 0.9906)
			(stroke
				(width 0.1)
				(type default)
			)
			(layer "F.Fab")
		)
		(pad "1" smd rect
			(at 0 0 90)
			(size 0.508 0.508)
			(layers "F.Cu" "F.Mask" "F.Paste")
			(net "VR_PVDDQ_KLM_AIREF1")
		)
		(pad "2" smd rect
			(at 0 0.889 90)
			(size 0.508 0.508)
			(layers "F.Cu" "F.Mask" "F.Paste")
			(net "ISENSE_PVDDQ_KLM_PH1_IMON")
		)
		(zone
			(layer "F.Cu")
			(hatch none 0.5)
			(connect_pads
				(clearance 0)
			)
			(min_thickness 0.25)
			(keepout
				(tracks allowed)
				(vias not_allowed)
				(pads allowed)
				(copperpour not_allowed)
				(footprints allowed)
			)
			(placement
				(enabled no)
				(sheetname "")
			)
			(fill
				(thermal_gap 0.5)
				(thermal_bridge_width 0.5)
				(island_removal_mode 0)
			)
			(polygon
				(pts
					(xy -0.779526 -123.819666) (xy -0.779526 -124.327666) (xy -0.398526 -124.327666) (xy -0.398526 -123.819666)
				)
			)
		)
		(zone
			(layer "F.Cu")
			(hatch none 0.5)
			(connect_pads
				(clearance 0)
			)
			(min_thickness 0.25)
			(keepout
				(tracks not_allowed)
				(vias allowed)
				(pads allowed)
				(copperpour not_allowed)
				(footprints allowed)
			)
			(placement
				(enabled no)
				(sheetname "")
			)
			(fill
				(thermal_gap 0.5)
				(thermal_bridge_width 0.5)
				(island_removal_mode 0)
			)
			(polygon
				(pts
					(xy -0.398526 -123.819666) (xy -0.398526 -124.327666) (xy -0.779526 -124.327666) (xy -0.779526 -123.819666)
				)
			)
		)
	)
	(footprint ""
		(layer "F.Cu")
		(at 2.397506 -138.184382 90)
		(property "Reference" "EU1A2"
			(at 3.495548 -1.432306 0)
			(unlocked yes)
			(layer "F.SilkS")
			(effects
				(font
					(size 0.7874 0.5842)
					(thickness 0.1524)
				)
			)
		)
		(property "Value" ""
			(at 0 0 90)
			(layer "F.Fab")
			(effects
				(font
					(size 1.27 1.27)
				)
			)
		)
		(duplicate_pad_numbers_are_jumpers no)
		(fp_line
			(start 2.9718 -3.5052)
			(end 2.9718 3.429)
			(stroke
				(width 0.1524)
				(type default)
			)
			(layer "F.SilkS")
		)
		(fp_line
			(start -3.0099 -3.5052)
			(end 2.9718 -3.5052)
			(stroke
				(width 0.1524)
				(type default)
			)
			(layer "F.SilkS")
		)
		(fp_line
			(start 2.9718 3.429)
			(end -3.0099 3.429)
			(stroke
				(width 0.1524)
				(type default)
			)
			(layer "F.SilkS")
		)
		(fp_line
			(start -3.0099 3.429)
			(end -3.0099 -3.5052)
			(stroke
				(width 0.1524)
				(type default)
			)
			(layer "F.SilkS")
		)
		(fp_circle
			(center -3.057398 -2.678684)
			(end -3.057398 -2.551684)
			(stroke
				(width 0.254)
				(type default)
			)
			(fill no)
			(layer "F.SilkS")
		)
		(fp_poly
			(pts
				(xy -2.9972 -3.4925) (xy -2.9972 -2.6924) (xy -2.1971 -3.4925)
			)
			(stroke
				(width 0)
				(type default)
			)
			(fill yes)
			(layer "F.SilkS")
		)
		(fp_poly
			(pts
				(xy -2.549906 -3.050032) (xy -2.549906 3.050032) (xy 2.549906 3.050032) (xy 2.549906 -3.050032)
			)
			(stroke
				(width 0)
				(type default)
			)
			(fill no)
			(layer "F.CrtYd")
		)
		(fp_line
			(start 2.549906 -3.050032)
			(end 2.549906 3.050032)
			(stroke
				(width 0.1)
				(type default)
			)
			(layer "F.Fab")
		)
		(fp_line
			(start -2.549906 -3.050032)
			(end 2.549906 -3.050032)
			(stroke
				(width 0.1)
				(type default)
			)
			(layer "F.Fab")
		)
		(fp_line
			(start 2.549906 3.050032)
			(end -2.549906 3.050032)
			(stroke
				(width 0.1)
				(type default)
			)
			(layer "F.Fab")
		)
		(fp_line
			(start -2.549906 3.050032)
			(end -2.549906 -3.050032)
			(stroke
				(width 0.1)
				(type default)
			)
			(layer "F.Fab")
		)
		(fp_circle
			(center -3.057398 -2.678684)
			(end -3.057398 -2.551684)
			(stroke
				(width 0.254)
				(type default)
			)
			(fill no)
			(layer "F.Fab")
		)
		(pad "1" smd rect
			(at -2.39522 -2.279904 90)
			(size 0.7112 0.254)
			(layers "F.Cu" "F.Mask" "F.Paste")
			(net "PVDDQ_KLM")
		)
		(pad "2" smd rect
			(at -2.39522 -1.83007 90)
			(size 0.7112 0.254)
			(layers "F.Cu" "F.Mask" "F.Paste")
			(net "GND")
		)
		(pad "3" smd rect
			(at -2.39522 -1.379982 90)
			(size 0.7112 0.254)
			(layers "F.Cu" "F.Mask" "F.Paste")
			(net "VR_PVDDQ_KLM_PH1_VCIN")
		)
		(pad "4" smd rect
			(at -2.39522 -0.929894 90)
			(size 0.7112 0.254)
			(layers "F.Cu" "F.Mask" "F.Paste")
			(net "P5V_STBY")
		)
		(pad "5" smd rect
			(at -2.39522 -0.48006 90)
			(size 0.7112 0.254)
			(layers "F.Cu" "F.Mask" "F.Paste")
			(net "GND")
		)
		(pad "6" smd rect
			(at -2.39522 -0.029972 90)
			(size 0.7112 0.254)
			(layers "F.Cu" "F.Mask" "F.Paste")
			(net "TP_PVDDQ_KLM_PH1_GL_0")
		)
		(pad "7" smd custom
			(at 0.016764 1.145032 90)
			(size 0.53975 0.53975)
			(layers "F.Cu" "F.Mask" "F.Paste")
			(net "GND")
			(options
				(clearance outline)
				(anchor circle)
			)
			(primitives
				(gr_poly
					(pts
						(xy -2.7051 1.0795) (xy -2.7051 -0.3683) (xy -0.9271 -0.3683) (xy -0.9271 -1.0795) (xy 2.7051 -1.0795)
						(xy 2.7051 1.0795)
					)
					(width 0)
					(fill yes)
				)
			)
		)
		(pad "10" smd rect
			(at -0.008382 2.874772 90)
			(size 4.3434 0.6096)
			(layers "F.Cu" "F.Mask" "F.Paste")
			(net "VR_PVDDQ_KLM_PH1_SW")
		)
		(pad "25" smd rect
			(at 1.548384 -1.283208 90)
			(size 2.3368 2.0066)
			(layers "F.Cu" "F.Mask" "F.Paste")
			(net "VR_FET_SW_P12V_STBY_PVDDQ_KLM")
		)
		(pad "30" smd rect
			(at 2.050034 -2.895092 90)
			(size 0.254 0.7112)
			(layers "F.Cu" "F.Mask" "F.Paste")
			(net "VR_FET_SW_P12V_STBY_PVDDQ_KLM")
		)
		(pad "31" smd rect
			(at 1.599946 -2.895092 90)
			(size 0.254 0.7112)
			(layers "F.Cu" "F.Mask" "F.Paste")
			(net "Net_372")
		)
		(pad "32" smd rect
			(at 1.150112 -2.895092 90)
			(size 0.254 0.7112)
			(layers "F.Cu" "F.Mask" "F.Paste")
			(net "VR_PVDDQ_KLM_PH1_PHASE")
		)
		(pad "33" smd rect
			(at 0.700024 -2.895092 90)
			(size 0.254 0.7112)
			(layers "F.Cu" "F.Mask" "F.Paste")
			(net "VR_PVDDQ_KLM_PH1_BOOT_R")
		)
		(pad "34" smd rect
			(at 0.249936 -2.895092 90)
			(size 0.254 0.7112)
			(layers "F.Cu" "F.Mask" "F.Paste")
			(net "VR_PVDDQ_KLM_PWM1")
		)
		(pad "35" smd rect
			(at -0.199898 -2.895092 90)
			(size 0.254 0.7112)
			(layers "F.Cu" "F.Mask" "F.Paste")
			(net "P5V_STBY")
		)
		(pad "36" smd rect
			(at -0.649986 -2.895092 90)
			(size 0.254 0.7112)
			(layers "F.Cu" "F.Mask" "F.Paste")
			(net "A_TSENSE_PVDDQ_KLM")
		)
		(pad "37" smd rect
			(at -1.100074 -2.895092 90)
			(size 0.254 0.7112)
			(layers "F.Cu" "F.Mask" "F.Paste")
			(net "VR_PVDDQ_KLM_PH1_OCSET")
		)
		(pad "38" smd rect
			(at -1.549908 -2.895092 90)
			(size 0.254 0.7112)
			(layers "F.Cu" "F.Mask" "F.Paste")
			(net "ISENSE_PVDDQ_KLM_PH1_IMON")
		)
		(pad "39" smd rect
			(at -1.999996 -2.895092 90)
			(size 0.254 0.7112)
			(layers "F.Cu" "F.Mask" "F.Paste")
			(net "VR_PVDDQ_KLM_AIREF1")
		)
		(pad "40" smd rect
			(at -0.871728 -1.283208 90)
			(size 1.8034 2.0066)
			(layers "F.Cu" "F.Mask" "F.Paste")
			(net "GND")
		)
		(pad "41" smd rect
			(at -1.533906 0.247904 90)
			(size 0.508 0.3556)
			(layers "F.Cu" "F.Mask" "F.Paste")
			(net "TP_PVDDQ_KLM_PH1_GL_1")
		)
	)
	(footprint ""
		(layer "F.Cu")
		(at 19.558 -70.866)
		(property "Reference" "C1D26"
			(at 0 0 0)
			(layer "F.SilkS")
			(hide yes)
			(effects
				(font
					(size 1.27 1.27)
				)
			)
		)
		(property "Value" ""
			(at 0 0 0)
			(layer "F.Fab")
			(effects
				(font
					(size 1.27 1.27)
				)
			)
		)
		(duplicate_pad_numbers_are_jumpers no)
		(fp_poly
			(pts
				(xy 0.3048 -0.1016) (xy 0.3048 0.9906) (xy -0.3048 0.9906) (xy -0.3048 -0.1016)
			)
			(stroke
				(width 0)
				(type default)
			)
			(fill no)
			(layer "F.CrtYd")
		)
		(fp_line
			(start -0.3048 -0.1016)
			(end -0.3048 0.9906)
			(stroke
				(width 0.1)
				(type default)
			)
			(layer "F.Fab")
		)
		(fp_line
			(start -0.3048 0.9906)
			(end 0.3048 0.9906)
			(stroke
				(width 0.1)
				(type default)
			)
			(layer "F.Fab")
		)
		(fp_line
			(start 0.3048 -0.1016)
			(end -0.3048 -0.1016)
			(stroke
				(width 0.1)
				(type default)
			)
			(layer "F.Fab")
		)
		(fp_line
			(start 0.3048 0.9906)
			(end 0.3048 -0.1016)
			(stroke
				(width 0.1)
				(type default)
			)
			(layer "F.Fab")
		)
		(pad "1" smd rect
			(at 0 0)
			(size 0.508 0.508)
			(layers "F.Cu" "F.Mask" "F.Paste")
			(net "A_HSC_UV")
		)
		(pad "2" smd rect
			(at 0 0.889)
			(size 0.508 0.508)
			(layers "F.Cu" "F.Mask" "F.Paste")
			(net "AGND_HSC")
		)
		(zone
			(layer "F.Cu")
			(hatch none 0.5)
			(connect_pads
				(clearance 0)
			)
			(min_thickness 0.25)
			(keepout
				(tracks allowed)
				(vias not_allowed)
				(pads allowed)
				(copperpour not_allowed)
				(footprints allowed)
			)
			(placement
				(enabled no)
				(sheetname "")
			)
			(fill
				(thermal_gap 0.5)
				(thermal_bridge_width 0.5)
				(island_removal_mode 0)
			)
			(polygon
				(pts
					(xy 19.304 -70.612) (xy 19.812 -70.612) (xy 19.812 -70.231) (xy 19.304 -70.231)
				)
			)
		)
		(zone
			(layer "F.Cu")
			(hatch none 0.5)
			(connect_pads
				(clearance 0)
			)
			(min_thickness 0.25)
			(keepout
				(tracks not_allowed)
				(vias allowed)
				(pads allowed)
				(copperpour not_allowed)
				(footprints allowed)
			)
			(placement
				(enabled no)
				(sheetname "")
			)
			(fill
				(thermal_gap 0.5)
				(thermal_bridge_width 0.5)
				(island_removal_mode 0)
			)
			(polygon
				(pts
					(xy 19.304 -70.231) (xy 19.812 -70.231) (xy 19.812 -70.612) (xy 19.304 -70.612)
				)
			)
		)
	)
	(footprint ""
		(layer "F.Cu")
		(at 477.978724 -150.256494)
		(property "Reference" "R1L2"
			(at 0 0 0)
			(layer "F.SilkS")
			(hide yes)
			(effects
				(font
					(size 1.27 1.27)
				)
			)
		)
		(property "Value" ""
			(at 0 0 0)
			(layer "F.Fab")
			(effects
				(font
					(size 1.27 1.27)
				)
			)
		)
		(duplicate_pad_numbers_are_jumpers no)
		(fp_poly
			(pts
				(xy -0.2794 -0.1016) (xy 0.2794 -0.1016) (xy 0.2794 0.9906) (xy -0.2794 0.9906)
			)
			(stroke
				(width 0)
				(type default)
			)
			(fill no)
			(layer "F.CrtYd")
		)
		(fp_line
			(start -0.2794 -0.1016)
			(end -0.2794 0.9906)
			(stroke
				(width 0.1)
				(type default)
			)
			(layer "F.Fab")
		)
		(fp_line
			(start -0.2794 0.9906)
			(end 0.2794 0.9906)
			(stroke
				(width 0.1)
				(type default)
			)
			(layer "F.Fab")
		)
		(fp_line
			(start 0.2794 -0.1016)
			(end -0.2794 -0.1016)
			(stroke
				(width 0.1)
				(type default)
			)
			(layer "F.Fab")
		)
		(fp_line
			(start 0.2794 0.9906)
			(end 0.2794 -0.1016)
			(stroke
				(width 0.1)
				(type default)
			)
			(layer "F.Fab")
		)
		(pad "1" smd rect
			(at 0 0)
			(size 0.508 0.508)
			(layers "F.Cu" "F.Mask" "F.Paste")
			(net "FM_CPLD_DBG_PWR_EN_N")
		)
		(pad "2" smd rect
			(at 0 0.889)
			(size 0.508 0.508)
			(layers "F.Cu" "F.Mask" "F.Paste")
			(net "FM_CPLD_DBG_PWR_EN_R_N")
		)
		(zone
			(layer "F.Cu")
			(hatch none 0.5)
			(connect_pads
				(clearance 0)
			)
			(min_thickness 0.25)
			(keepout
				(tracks allowed)
				(vias not_allowed)
				(pads allowed)
				(copperpour not_allowed)
				(footprints allowed)
			)
			(placement
				(enabled no)
				(sheetname "")
			)
			(fill
				(thermal_gap 0.5)
				(thermal_bridge_width 0.5)
				(island_removal_mode 0)
			)
			(polygon
				(pts
					(xy 477.724724 -150.002494) (xy 478.232724 -150.002494) (xy 478.232724 -149.621494) (xy 477.724724 -149.621494)
				)
			)
		)
		(zone
			(layer "F.Cu")
			(hatch none 0.5)
			(connect_pads
				(clearance 0)
			)
			(min_thickness 0.25)
			(keepout
				(tracks not_allowed)
				(vias allowed)
				(pads allowed)
				(copperpour not_allowed)
				(footprints allowed)
			)
			(placement
				(enabled no)
				(sheetname "")
			)
			(fill
				(thermal_gap 0.5)
				(thermal_bridge_width 0.5)
				(island_removal_mode 0)
			)
			(polygon
				(pts
					(xy 477.724724 -149.621494) (xy 478.232724 -149.621494) (xy 478.232724 -150.002494) (xy 477.724724 -150.002494)
				)
			)
		)
	)
)
